FILE_TYPE = MACRO_DRAWING;
SET COLOR_WIRE YELLOW;
SET COLOR_PROP ORANGE;
SET COLOR_DOT WHITE;
SET COLOR_ARC YELLOW;
SET COLOR_BODY GREEN;
SET COLOR_NOTE PURPLE;
SET PROP_DISPLAY VALUE;
SET PAGE_NUMBER P125;
FORCEADD QUANTA_TITLE_BLOCK_C..1
(0 0);
FORCEPROP 1 LAST CUSTOM_TXT_CDS <NAME_2>
J 0
(-3175 50);
FORCEPROP 1 LAST CUSTOM_TXT_CDS <NAME_1>
J 0
(-3175 175);
FORCEPROP 1 LAST CUSTOM_TXT_CDS <Q_NUMBER>
J 0
(-1403 103);
DISPLAY 1.212766 (-1403 103);
FORCEPROP 1 LAST CUSTOM_TXT_CDS <Q_PROJ>
J 0
(-2382 102);
DISPLAY 1.212766 (-2382 102);
FORCEPROP 1 LAST CUSTOM_TXT_CDS <Q_REV>
J 0
(-184 103);
DISPLAY 1.212766 (-184 103);
FORCEPROP 1 LAST CUSTOM_TXT_CDS <CON_LAST_MODIFIED>
J 0
(-1885 15);
DISPLAY 0.978723 (-1885 15);
FORCEPROP 1 LAST CUSTOM_TXT_CDS <CON_PAGE_NUM> OF <CON_TOTAL_PAGES>
J 0
(-446 18);
DISPLAY 0.978723 (-446 18);
FORCEPROP 1 LAST Q_TITLE E1.S CONN2
J 0
(-9300 50);
DISPLAY 2.446809 (-9300 50);
PAINT GREEN (-9300 50);
FORCEPROP 1 LAST Q_DEPT BU9
J 1
(-3763 49);
DISPLAY 1.957447 (-3763 49);
PAINT GREEN (-3763 49);
FORCEPROP 1 LAST CDS_LMAN_SYM_OUTLINE -9475,6775,100,-125
J 0
(0 0);
DISPLAY 0.468085 (0 0);
PAINT GREEN (0 0);
DISPLAY INVISIBLE (0 0);
FORCEPROP 2 LAST CDS_LIB pure_quanta
J 0
(0 0);
DISPLAY INVISIBLE (0 0);
FORCEPROP 2 LAST PAGE_BORDER TRUE
J 0
(-7890 5250);
DISPLAY 0.638298 (-7890 5250);
PAINT PINK (-7890 5250);
DISPLAY INVISIBLE (-7890 5250);
FORCEPROP 1 LAST COMMENT_BODY TRUE
J 0
(12 -13);
DISPLAY 0.978723 (12 -13);
PAINT GREEN (12 -13);
DISPLAY INVISIBLE (12 -13);
FORCEPROP 2 LAST CDS_XR_PAGE_TITLE CR-125 : @T6G_MB_LIB.T6G(SCH_1):PAGE125
J 0
(-7890 5250);
DISPLAY 0.638298 (-7890 5250);
PAINT PINK (-7890 5250);
DISPLAY INVISIBLE (-7890 5250);
FORCEPROP 2 LAST CUSTOM_TXT_CDS <XR_PAGE_TITLE>
J 0
(-7890 5250);
DISPLAY 0.638298 (-7890 5250);
PAINT PINK (-7890 5250);
DISPLAY INVISIBLE (-7890 5250);
FORCEPROP 0 LAST CDS_CON_LAST_MODIFIED Wed Mar 09 18:12:28 2022
J 0
(-1885 15);
DISPLAY INVISIBLE (-1885 15);
QUIT
